(kicad_pcb
	(version 20221018)
	(generator pcbnew)
	(general
    (thickness 1.656)
  )
	(paper "A4")
	(title_block
    (title "SDI-MIPI Bridge")
    (date "2023-08-09")
    (rev "1.3.4")
    (company "Antmicro")
		(comment 9 "footprints 70-70 of 190")
	)
	(layers
    (0 "F.Cu" signal)
    (1 "In1.Cu" power)
    (2 "In2.Cu" power)
    (3 "In3.Cu" signal)
    (4 "In4.Cu" signal)
    (31 "B.Cu" signal)
    (32 "B.Adhes" user "B.Adhesive")
    (33 "F.Adhes" user "F.Adhesive")
    (34 "B.Paste" user)
    (35 "F.Paste" user)
    (36 "B.SilkS" user "B.Silkscreen")
    (37 "F.SilkS" user "F.Silkscreen")
    (38 "B.Mask" user)
    (39 "F.Mask" user)
    (40 "Dwgs.User" user "User.Drawings")
    (41 "Cmts.User" user "User.Comments")
    (42 "Eco1.User" user "User.Eco1")
    (43 "Eco2.User" user "User.Eco2")
    (44 "Edge.Cuts" user)
    (45 "Margin" user)
    (46 "B.CrtYd" user "B.Courtyard")
    (47 "F.CrtYd" user "F.Courtyard")
    (48 "B.Fab" user)
    (49 "F.Fab" user)
  )
	(footprint "sdi-mipi-bridge-footprints:R_0402_1005Metric" (layer "F.Cu")
    (at 142.1 110.925 -90)
    (descr "Resistor SMD 0402")
    (tags "resistor SMD 0402")
    (property "Author" "Antmicro")
    (property "License" "Apache-2.0")
    (property "MPN" "CR0402-FX-30R0GLF")
    (property "Manufacturer" "Bourns")
    (property "Sheetfile" "sdi-mipi-bridge.kicad_sch")
    (property "Sheetname" "")
    (property "Tolerance" "1%")
    (property "Val" "30R")
    (property "ki_description" "30R resistor in 0402 package with 1% tolerance")
    (attr smd)
    (fp_text reference "R96" (at -0.925 -0.35 -90) (layer "F.SilkS")
        (effects (font (size 0.65 0.65) (thickness 0.15)) (justify left bottom))
    )
    (fp_text value "R_30R_0402" (at 0 1.4 -90) (layer "F.Fab") hide
        (effects (font (size 0.7 0.7) (thickness 0.15)) (justify left bottom))
    )
    (fp_text user "${REFERENCE}" (at -0.95 3.168 -90) (layer "F.Fab") hide
        (effects (font (size 0.7 0.7) (thickness 0.15)) (justify left bottom))
    )
    (fp_text user "Author: Antmicro" (at -0.95 4.169 -90) (layer "F.Fab") hide
        (effects (font (size 0.7 0.7) (thickness 0.15)) (justify left bottom))
    )
    (fp_text user "License: Apache-2.0" (at -0.95 5.169 -90) (layer "F.Fab") hide
        (effects (font (size 0.7 0.7) (thickness 0.15)) (justify left bottom))
    )
    (fp_rect (start -0.93 -0.47) (end 0.93 0.47)
      (stroke (width 0.05) (type solid)) (fill none) (layer "F.CrtYd"))
    (fp_rect (start -0.5 -0.25) (end 0.5 0.25)
      (stroke (width 0.15) (type solid)) (fill none) (layer "F.Fab"))
    (pad "1" smd roundrect (at -0.485 0 270) (size 0.59 0.64) (layers "F.Cu" "F.Paste" "F.Mask") (roundrect_rratio 0.25)
      (net 102 "/SPI_SCK(SDA)") (pintype "passive"))
    (pad "2" smd roundrect (at 0.485 0 270) (size 0.59 0.64) (layers "F.Cu" "F.Paste" "F.Mask") (roundrect_rratio 0.25)
      (net 128 "Net-(U4-PB53{slash}SPI_SCK{slash}MCK{slash}SDA)") (pintype "passive"))
  )
)
